# TIMECARD (Time Appliance Project (Time Card)) — schematic netlist excerpt (pin names and nets, part order shuffled) for the footprints in the layout excerpt that follows; sources: Cadence DE-HDL packaged netlist, KiCad conversion of R4006-B0001-02_R01.brd

R142  RESISTOR  100OHM 1%  pkg SMC_0402R_H016  page 32 : \1\ = XP1R8V_FPGA_PG ; \2\ = R_XP5R0V_EN
R403  RESISTOR  10KOHM 1%  pkg SMC_0402R_H016  page 10 : \1\ = XP3R3V_FPGA ; \2\ = FPGA_TDO

(kicad_pcb
	(version 20260206)
	(generator "pcbnew")
	(generator_version "10.0")
	(general
		(thickness 1.6)
		(legacy_teardrops no)
	)
	(paper "A4")
	(title_block
		(title "timecard-production-celestica-r4006 — R4006-B0001-02_R01.brd")
		(comment 1 "Time Appliance Project (Time Card) / footprints 1033-1034 of 1113")
	)
	(layers
		(0 "F.Cu" signal "TOP")
		(4 "In1.Cu" signal "L02_GND1")
		(6 "In2.Cu" signal "L03_SIG1")
		(8 "In3.Cu" signal "L04_GND2")
		(10 "In4.Cu" signal "L05_VCC1")
		(12 "In5.Cu" signal "L06_VCC2")
		(14 "In6.Cu" signal "L07_GND3")
		(16 "In7.Cu" signal "L08_SIG2")
		(18 "In8.Cu" signal "L09_GND4")
		(2 "B.Cu" signal "BOTTOM")
		(9 "F.Adhes" user "F.Adhesive")
		(11 "B.Adhes" user "B.Adhesive")
		(13 "F.Paste" user "Package Geometry/Pastemask Top")
		(15 "B.Paste" user "Package Geometry/Pastemask Bottom")
		(5 "F.SilkS" user "Ref Des/Silkscreen Top")
		(7 "B.SilkS" user "Ref Des/Silkscreen Bottom")
		(1 "F.Mask" user "Board Geometry/Soldermask Top")
		(3 "B.Mask" user "Board Geometry/Soldermask Bottom")
		(17 "Dwgs.User" user "User.Drawings")
		(19 "Cmts.User" user "User.Comments")
		(21 "Eco1.User" user "User.Eco1")
		(23 "Eco2.User" user "User.Eco2")
		(25 "Edge.Cuts" user "Board Geometry/Outline")
		(27 "Margin" user)
		(31 "F.CrtYd" user "Package Geometry/Place Bound Top")
		(29 "B.CrtYd" user "Package Geometry/Place Bound Bottom")
		(35 "F.Fab" user "Ref Des/Assembly Top")
		(33 "B.Fab" user "Ref Des/Assembly Bottom")
	)
	(footprint ""
		(layer "B.Cu")
		(at 138.4808 -70.9168 90)
		(property "Reference" "R403"
			(at 0.9652 -4.78917 270)
			(unlocked yes)
			(layer "B.SilkS")
			(effects
				(font
					(size 0.7874 0.5842)
					(thickness 0.1524)
				)
				(justify mirror)
			)
		)
		(property "Value" "VAL*"
			(at -0.02032 2.13233 90)
			(unlocked yes)
			(layer "B.Fab")
			(hide yes)
			(effects
				(font
					(size 0.7874 0.5842)
					(thickness 0.1524)
				)
				(justify mirror)
			)
		)
		(property "Tolerance" "TOL*"
			(at -0.044704 3.05435 90)
			(unlocked yes)
			(layer "Cmts.User")
			(hide yes)
			(effects
				(font
					(size 0.7874 0.5842)
					(thickness 0.1524)
				)
				(justify mirror)
			)
		)
		(property "User Part Number" "PARTNUM*"
			(at -0.02032 4.024884 90)
			(unlocked yes)
			(layer "Cmts.User")
			(hide yes)
			(effects
				(font
					(size 0.7874 0.5842)
					(thickness 0.1524)
				)
				(justify mirror)
			)
		)
		(property "Device Type" "RESISTOR-G155-11002-01,10KOHM,A"
			(at -0.008382 1.210564 90)
			(unlocked yes)
			(layer "B.Fab")
			(hide yes)
			(effects
				(font
					(size 0.7874 0.5842)
					(thickness 0.1524)
				)
				(justify mirror)
			)
		)
		(duplicate_pad_numbers_are_jumpers no)
		(fp_line
			(start 1.143 -0.5588)
			(end 1.143 0.5588)
			(stroke
				(width 0.1)
				(type default)
			)
			(layer "B.SilkS")
		)
		(fp_line
			(start -1.143 -0.5588)
			(end 1.143 -0.5588)
			(stroke
				(width 0.1)
				(type default)
			)
			(layer "B.SilkS")
		)
		(fp_line
			(start 1.143 0.5588)
			(end -1.143 0.5588)
			(stroke
				(width 0.1)
				(type default)
			)
			(layer "B.SilkS")
		)
		(fp_line
			(start -1.143 0.5588)
			(end -1.143 -0.5588)
			(stroke
				(width 0.1)
				(type default)
			)
			(layer "B.SilkS")
		)
		(fp_rect
			(start 1.143 0.5588)
			(end -1.143 -0.5588)
			(stroke
				(width 0)
				(type default)
			)
			(fill no)
			(layer "B.CrtYd")
		)
		(fp_line
			(start 0.508 -0.3048)
			(end 0.508 0.3048)
			(stroke
				(width 0.1)
				(type default)
			)
			(layer "B.Fab")
		)
		(fp_line
			(start -0.508 -0.3048)
			(end 0.508 -0.3048)
			(stroke
				(width 0.1)
				(type default)
			)
			(layer "B.Fab")
		)
		(fp_line
			(start 0.508 0.3048)
			(end -0.508 0.3048)
			(stroke
				(width 0.1)
				(type default)
			)
			(layer "B.Fab")
		)
		(fp_line
			(start -0.508 0.3048)
			(end -0.508 -0.3048)
			(stroke
				(width 0.1)
				(type default)
			)
			(layer "B.Fab")
		)
		(pad "1" smd rect
			(at 0.5334 0 270)
			(size 0.7112 0.6096)
			(layers "B.Cu" "B.Mask" "B.Paste")
			(net "XP3R3V_FPGA")
		)
		(pad "2" smd rect
			(at -0.5334 0 270)
			(size 0.7112 0.6096)
			(layers "B.Cu" "B.Mask" "B.Paste")
			(net "FPGA_TDO")
		)
		(zone
			(layer "B.Cu")
			(hatch none 0.5)
			(connect_pads
				(clearance 0)
			)
			(min_thickness 0.25)
			(keepout
				(tracks not_allowed)
				(vias allowed)
				(pads allowed)
				(copperpour not_allowed)
				(footprints allowed)
			)
			(placement
				(enabled no)
				(sheetname "")
			)
			(fill
				(thermal_gap 0.5)
				(thermal_bridge_width 0.5)
				(island_removal_mode 0)
			)
			(polygon
				(pts
					(xy 138.7856 -70.993) (xy 138.176 -70.993) (xy 138.176 -70.8406) (xy 138.7856 -70.8406)
				)
			)
		)
		(zone
			(layer "B.Cu")
			(hatch none 0.5)
			(connect_pads
				(clearance 0)
			)
			(min_thickness 0.25)
			(keepout
				(tracks allowed)
				(vias not_allowed)
				(pads allowed)
				(copperpour not_allowed)
				(footprints allowed)
			)
			(placement
				(enabled no)
				(sheetname "")
			)
			(fill
				(thermal_gap 0.5)
				(thermal_bridge_width 0.5)
				(island_removal_mode 0)
			)
			(polygon
				(pts
					(xy 138.7856 -70.993) (xy 138.176 -70.993) (xy 138.176 -70.8406) (xy 138.7856 -70.8406)
				)
			)
		)
	)
	(footprint ""
		(layer "B.Cu")
		(at 36.9824 -99.0854 180)
		(property "Reference" "R142"
			(at 4.4196 -0.62357 0)
			(unlocked yes)
			(layer "B.SilkS")
			(effects
				(font
					(size 0.7874 0.5842)
					(thickness 0.1524)
				)
				(justify mirror)
			)
		)
		(property "Value" "VAL*"
			(at -0.02032 2.13233 180)
			(unlocked yes)
			(layer "B.Fab")
			(hide yes)
			(effects
				(font
					(size 0.7874 0.5842)
					(thickness 0.1524)
				)
				(justify mirror)
			)
		)
		(property "Device Type" "RESISTOR-G155-11000-01,100OHM,A"
			(at -0.008382 1.210564 180)
			(unlocked yes)
			(layer "B.Fab")
			(hide yes)
			(effects
				(font
					(size 0.7874 0.5842)
					(thickness 0.1524)
				)
				(justify mirror)
			)
		)
		(property "User Part Number" "PARTNUM*"
			(at -0.02032 4.024884 180)
			(unlocked yes)
			(layer "Cmts.User")
			(hide yes)
			(effects
				(font
					(size 0.7874 0.5842)
					(thickness 0.1524)
				)
				(justify mirror)
			)
		)
		(property "Tolerance" "TOL*"
			(at -0.044704 3.05435 180)
			(unlocked yes)
			(layer "Cmts.User")
			(hide yes)
			(effects
				(font
					(size 0.7874 0.5842)
					(thickness 0.1524)
				)
				(justify mirror)
			)
		)
		(duplicate_pad_numbers_are_jumpers no)
		(fp_line
			(start 1.143 0.5588)
			(end -1.143 0.5588)
			(stroke
				(width 0.1)
				(type default)
			)
			(layer "B.SilkS")
		)
		(fp_line
			(start 1.143 -0.5588)
			(end 1.143 0.5588)
			(stroke
				(width 0.1)
				(type default)
			)
			(layer "B.SilkS")
		)
		(fp_line
			(start -1.143 0.5588)
			(end -1.143 -0.5588)
			(stroke
				(width 0.1)
				(type default)
			)
			(layer "B.SilkS")
		)
		(fp_line
			(start -1.143 -0.5588)
			(end 1.143 -0.5588)
			(stroke
				(width 0.1)
				(type default)
			)
			(layer "B.SilkS")
		)
		(fp_rect
			(start -1.143 0.5588)
			(end 1.143 -0.5588)
			(stroke
				(width 0)
				(type default)
			)
			(fill no)
			(layer "B.CrtYd")
		)
		(fp_line
			(start 0.508 0.3048)
			(end -0.508 0.3048)
			(stroke
				(width 0.1)
				(type default)
			)
			(layer "B.Fab")
		)
		(fp_line
			(start 0.508 -0.3048)
			(end 0.508 0.3048)
			(stroke
				(width 0.1)
				(type default)
			)
			(layer "B.Fab")
		)
		(fp_line
			(start -0.508 0.3048)
			(end -0.508 -0.3048)
			(stroke
				(width 0.1)
				(type default)
			)
			(layer "B.Fab")
		)
		(fp_line
			(start -0.508 -0.3048)
			(end 0.508 -0.3048)
			(stroke
				(width 0.1)
				(type default)
			)
			(layer "B.Fab")
		)
		(pad "1" smd rect
			(at 0.5334 0)
			(size 0.7112 0.6096)
			(layers "B.Cu" "B.Mask" "B.Paste")
			(net "XP1R8V_FPGA_PG")
		)
		(pad "2" smd rect
			(at -0.5334 0)
			(size 0.7112 0.6096)
			(layers "B.Cu" "B.Mask" "B.Paste")
			(net "R_XP5R0V_EN")
		)
		(zone
			(layer "B.Cu")
			(hatch none 0.5)
			(connect_pads
				(clearance 0)
			)
			(min_thickness 0.25)
			(keepout
				(tracks allowed)
				(vias not_allowed)
				(pads allowed)
				(copperpour not_allowed)
				(footprints allowed)
			)
			(placement
				(enabled no)
				(sheetname "")
			)
			(fill
				(thermal_gap 0.5)
				(thermal_bridge_width 0.5)
				(island_removal_mode 0)
			)
			(polygon
				(pts
					(xy 37.0586 -99.3902) (xy 36.9062 -99.3902) (xy 36.9062 -98.7806) (xy 37.0586 -98.7806)
				)
			)
		)
	)
)
